# T6G (Grand Teton) — schematic netlist excerpt (pin names and nets, part order shuffled) for the footprints in the layout excerpt that follows; sources: Cadence DE-HDL packaged netlist, KiCad conversion of 04192023_DAF0TMB3IC0_F0TG_MB_C_brd_V02_OCP.brd

H31  HOLE  EMPTY  pkg TH  page 230 : \1\ = GND
R682  Q_RES  33.2 1% CHIP  pkg 0201LF  page 300 : A = SMB_RT_CPU0_P2_ROM_R_SCL ; B = SMB_RT_CPU0_P2_ROM_SCL
R4141  Q_RES  100K 1% CHIP  pkg 0402LF  page 125 : A = P3V3_AUX ; B = GPU_3V3IO_RSVD5_FFU_ISO
H5  HOLE  EMPTY  pkg TH  page 230 : \1\ = GND

(kicad_pcb
	(version 20260206)
	(generator "pcbnew")
	(generator_version "10.0")
	(general
		(thickness 1.6)
		(legacy_teardrops no)
	)
	(paper "A4")
	(title_block
		(title "04192023_DAF0TMB3IC0_F0TG_MB_C_brd_V02_OCP.brd")
		(comment 1 "Grand Teton / footprints 3453-3456 of 8354")
	)
	(layers
		(0 "F.Cu" signal "TOP")
		(4 "In1.Cu" signal "GND")
		(6 "In2.Cu" signal "IN1")
		(8 "In3.Cu" signal "GND1")
		(10 "In4.Cu" signal "IN2")
		(12 "In5.Cu" signal "GND2")
		(14 "In6.Cu" signal "IN3")
		(16 "In7.Cu" signal "GND3")
		(18 "In8.Cu" signal "VCC")
		(20 "In9.Cu" signal "VCC1")
		(22 "In10.Cu" signal "GND4")
		(24 "In11.Cu" signal "IN4")
		(26 "In12.Cu" signal "GND5")
		(28 "In13.Cu" signal "IN5")
		(30 "In14.Cu" signal "GND6")
		(32 "In15.Cu" signal "IN6")
		(34 "In16.Cu" signal "GND7")
		(2 "B.Cu" signal "BOTTOM")
		(9 "F.Adhes" user "F.Adhesive")
		(11 "B.Adhes" user "B.Adhesive")
		(13 "F.Paste" user "Package Geometry/Pastemask Top")
		(15 "B.Paste" user "Package Geometry/Pastemask Bottom")
		(5 "F.SilkS" user "Ref Des/Silkscreen Top")
		(7 "B.SilkS" user "Ref Des/Silkscreen Bottom")
		(1 "F.Mask" user "Board Geometry/Soldermask Top")
		(3 "B.Mask" user "Board Geometry/Soldermask Bottom")
		(17 "Dwgs.User" user "User.Drawings")
		(19 "Cmts.User" user "User.Comments")
		(21 "Eco1.User" user "User.Eco1")
		(23 "Eco2.User" user "User.Eco2")
		(25 "Edge.Cuts" user "Board Geometry/Outline")
		(27 "Margin" user)
		(31 "F.CrtYd" user "Package Geometry/Place Bound Top")
		(29 "B.CrtYd" user "Package Geometry/Place Bound Bottom")
		(35 "F.Fab" user "Ref Des/Assembly Top")
		(33 "B.Fab" user "Ref Des/Assembly Bottom")
	)
	(footprint ""
		(layer "F.Cu")
		(at 308.420516 -439.276744 -90)
		(property "Reference" "R4141"
			(at 0 0 270)
			(layer "F.SilkS")
			(hide yes)
			(effects
				(font
					(size 1.27 1.27)
				)
			)
		)
		(property "Value" ""
			(at 0 0 270)
			(layer "F.Fab")
			(effects
				(font
					(size 1.27 1.27)
				)
			)
		)
		(duplicate_pad_numbers_are_jumpers no)
		(fp_line
			(start -0.7874 0.4064)
			(end -0.7874 -0.4064)
			(stroke
				(width 0.1524)
				(type default)
			)
			(layer "F.SilkS")
		)
		(fp_line
			(start 0.7874 0.4064)
			(end -0.7874 0.4064)
			(stroke
				(width 0.1524)
				(type default)
			)
			(layer "F.SilkS")
		)
		(fp_line
			(start -0.7874 -0.4064)
			(end 0.7874 -0.4064)
			(stroke
				(width 0.1524)
				(type default)
			)
			(layer "F.SilkS")
		)
		(fp_line
			(start 0.7874 -0.4064)
			(end 0.7874 0.4064)
			(stroke
				(width 0.1524)
				(type default)
			)
			(layer "F.SilkS")
		)
		(fp_line
			(start -0.67945 0.3048)
			(end -0.67945 -0.305054)
			(stroke
				(width 0.1)
				(type default)
			)
			(layer "F.Fab")
		)
		(fp_line
			(start -0.12065 0.3048)
			(end -0.67945 0.3048)
			(stroke
				(width 0.1)
				(type default)
			)
			(layer "F.Fab")
		)
		(fp_line
			(start 0.120396 0.3048)
			(end 0.120396 0.2794)
			(stroke
				(width 0.1)
				(type default)
			)
			(layer "F.Fab")
		)
		(fp_line
			(start 0.67945 0.3048)
			(end 0.120396 0.3048)
			(stroke
				(width 0.1)
				(type default)
			)
			(layer "F.Fab")
		)
		(fp_line
			(start -0.12065 0.2794)
			(end -0.12065 0.3048)
			(stroke
				(width 0.1)
				(type default)
			)
			(layer "F.Fab")
		)
		(fp_line
			(start 0.120396 0.2794)
			(end -0.12065 0.2794)
			(stroke
				(width 0.1)
				(type default)
			)
			(layer "F.Fab")
		)
		(fp_line
			(start -0.12065 -0.2794)
			(end 0.12065 -0.2794)
			(stroke
				(width 0.1)
				(type default)
			)
			(layer "F.Fab")
		)
		(fp_line
			(start 0.12065 -0.2794)
			(end 0.12065 -0.3048)
			(stroke
				(width 0.1)
				(type default)
			)
			(layer "F.Fab")
		)
		(fp_line
			(start 0.12065 -0.3048)
			(end 0.67945 -0.3048)
			(stroke
				(width 0.1)
				(type default)
			)
			(layer "F.Fab")
		)
		(fp_line
			(start 0.67945 -0.3048)
			(end 0.67945 0.3048)
			(stroke
				(width 0.1)
				(type default)
			)
			(layer "F.Fab")
		)
		(fp_line
			(start -0.67945 -0.305054)
			(end -0.12065 -0.305054)
			(stroke
				(width 0.1)
				(type default)
			)
			(layer "F.Fab")
		)
		(fp_line
			(start -0.12065 -0.305054)
			(end -0.12065 -0.2794)
			(stroke
				(width 0.1)
				(type default)
			)
			(layer "F.Fab")
		)
		(pad "1" smd circle
			(at -0.40005 0 270)
			(size 0 0)
			(layers "F.Cu" "F.Mask" "F.Paste")
			(net "P3V3_AUX")
		)
		(pad "2" smd circle
			(at 0.40005 0 270)
			(size 0 0)
			(layers "F.Cu" "F.Mask" "F.Paste")
			(net "GPU_3V3IO_RSVD5_FFU_ISO")
		)
	)
	(footprint ""
		(layer "F.Cu")
		(at 420.658544 -423.744644 90)
		(property "Reference" "R682"
			(at 0 0 90)
			(layer "F.SilkS")
			(hide yes)
			(effects
				(font
					(size 1.27 1.27)
				)
			)
		)
		(property "Value" ""
			(at 0 0 90)
			(layer "F.Fab")
			(effects
				(font
					(size 1.27 1.27)
				)
			)
		)
		(duplicate_pad_numbers_are_jumpers no)
		(fp_line
			(start 0.32512 -0.175006)
			(end 0.32512 0.175006)
			(stroke
				(width 0.1)
				(type default)
			)
			(layer "F.Fab")
		)
		(fp_line
			(start -0.32512 -0.175006)
			(end 0.32512 -0.175006)
			(stroke
				(width 0.1)
				(type default)
			)
			(layer "F.Fab")
		)
		(fp_line
			(start 0.32512 0.175006)
			(end -0.32512 0.175006)
			(stroke
				(width 0.1)
				(type default)
			)
			(layer "F.Fab")
		)
		(fp_line
			(start -0.32512 0.175006)
			(end -0.32512 -0.175006)
			(stroke
				(width 0.1)
				(type default)
			)
			(layer "F.Fab")
		)
		(pad "1" smd rect
			(at -0.2667 0 90)
			(size 0.3048 0.381)
			(layers "F.Cu" "F.Mask" "F.Paste")
			(net "SMB_RT_CPU0_P2_ROM_R_SCL")
		)
		(pad "2" smd rect
			(at 0.2667 0 270)
			(size 0.3048 0.381)
			(layers "F.Cu" "F.Mask" "F.Paste")
			(net "SMB_RT_CPU0_P2_ROM_SCL")
		)
	)
	(footprint ""
		(layer "F.Cu")
		(at 70.382892 -47.049944)
		(property "Reference" "H31"
			(at -1.7272 -4.511548 0)
			(unlocked yes)
			(layer "B.SilkS")
			(effects
				(font
					(size 0.7874 0.5842)
					(thickness 0.1524)
				)
				(justify left mirror)
			)
		)
		(property "Value" ""
			(at 0 0 0)
			(layer "F.Fab")
			(effects
				(font
					(size 1.27 1.27)
				)
			)
		)
		(duplicate_pad_numbers_are_jumpers no)
		(pad "1" thru_hole circle
			(at 0 0)
			(size 4.5212 4.5212)
			(drill 3.81)
			(layers "*.Cu" "*.Mask")
			(remove_unused_layers no)
			(net "GND")
			(clearance -0.1016)
			(padstack
				(mode front_inner_back)
				(layer "Inner"
					(shape circle)
					(size 5.6134 5.6134)
					(clearance -0.6477)
				)
				(layer "B.Cu"
					(shape circle)
					(size 8.001 8.001)
					(clearance -1.8415)
				)
			)
		)
	)
	(footprint ""
		(layer "F.Cu")
		(at 34.870136 -389.439912)
		(property "Reference" "H5"
			(at -0.69088 -4.273804 0)
			(unlocked yes)
			(layer "F.SilkS")
			(effects
				(font
					(size 0.7874 0.5842)
					(thickness 0.1524)
				)
				(justify left)
			)
		)
		(property "Value" ""
			(at 0 0 0)
			(layer "F.Fab")
			(effects
				(font
					(size 1.27 1.27)
				)
			)
		)
		(duplicate_pad_numbers_are_jumpers no)
		(pad "1" thru_hole circle
			(at 0 0)
			(size 6.1976 6.1976)
			(drill 3.7338)
			(layers "*.Cu" "*.Mask")
			(remove_unused_layers no)
			(net "GND")
			(clearance -0.9779)
			(padstack
				(mode front_inner_back)
				(layer "Inner"
					(shape circle)
					(size 5.5372 5.5372)
					(clearance -0.6477)
				)
				(layer "B.Cu"
					(shape circle)
					(size 6.1976 6.1976)
					(clearance -0.9779)
				)
			)
		)
	)
)
